# S9S_MB_2U (Grand Teton) — schematic netlist excerpt (pin names and nets, part order shuffled) for the footprints in the layout excerpt that follows; sources: Cadence DE-HDL packaged netlist, KiCad conversion of 03242023_DA0F0TMBIJ0_F0T_Motherboard_J_brd_V01_OCP.brd

PC2174  Q_CAP  0.1UF 25V 10% X7R  pkg 0402  page 163 : A = P12V_OCP_V3_2 ; B = GND
C2448  Q_CAP  10UF 4V 20% EMPTY  pkg C0603  page 284 : A = PVNN_TERM_CPU1 ; B = GND

(kicad_pcb
	(version 20260206)
	(generator "pcbnew")
	(generator_version "10.0")
	(general
		(thickness 1.6)
		(legacy_teardrops no)
	)
	(paper "A4")
	(title_block
		(title "03242023_DA0F0TMBIJ0_F0T_Motherboard_J_brd_V01_OCP.brd")
		(comment 1 "Grand Teton / footprints 2433-2434 of 6105")
	)
	(layers
		(0 "F.Cu" signal "TOP")
		(4 "In1.Cu" signal "GND")
		(6 "In2.Cu" signal "IN1")
		(8 "In3.Cu" signal "GND1")
		(10 "In4.Cu" signal "IN2")
		(12 "In5.Cu" signal "GND2")
		(14 "In6.Cu" signal "IN3")
		(16 "In7.Cu" signal "GND3")
		(18 "In8.Cu" signal "VCC")
		(20 "In9.Cu" signal "VCC1")
		(22 "In10.Cu" signal "GND4")
		(24 "In11.Cu" signal "IN4")
		(26 "In12.Cu" signal "GND5")
		(28 "In13.Cu" signal "IN5")
		(30 "In14.Cu" signal "GND6")
		(32 "In15.Cu" signal "IN6")
		(34 "In16.Cu" signal "GND7")
		(2 "B.Cu" signal "BOTTOM")
		(9 "F.Adhes" user "F.Adhesive")
		(11 "B.Adhes" user "B.Adhesive")
		(13 "F.Paste" user "Package Geometry/Pastemask Top")
		(15 "B.Paste" user "Package Geometry/Pastemask Bottom")
		(5 "F.SilkS" user "Ref Des/Silkscreen Top")
		(7 "B.SilkS" user "Ref Des/Silkscreen Bottom")
		(1 "F.Mask" user "Board Geometry/Soldermask Top")
		(3 "B.Mask" user "Board Geometry/Soldermask Bottom")
		(17 "Dwgs.User" user "User.Drawings")
		(19 "Cmts.User" user "User.Comments")
		(21 "Eco1.User" user "User.Eco1")
		(23 "Eco2.User" user "User.Eco2")
		(25 "Edge.Cuts" user "Board Geometry/Outline")
		(27 "Margin" user)
		(31 "F.CrtYd" user "Package Geometry/Place Bound Top")
		(29 "B.CrtYd" user "Package Geometry/Place Bound Bottom")
		(35 "F.Fab" user "Ref Des/Assembly Top")
		(33 "B.Fab" user "Ref Des/Assembly Bottom")
	)
	(footprint ""
		(layer "F.Cu")
		(at 69.917818 -25.192482)
		(property "Reference" "PC2174"
			(at 0 0 0)
			(layer "F.SilkS")
			(hide yes)
			(effects
				(font
					(size 1.27 1.27)
				)
			)
		)
		(property "Value" ""
			(at 0 0 0)
			(layer "F.Fab")
			(effects
				(font
					(size 1.27 1.27)
				)
			)
		)
		(duplicate_pad_numbers_are_jumpers no)
		(fp_line
			(start -0.7874 -0.4064)
			(end 0.7874 -0.4064)
			(stroke
				(width 0.1524)
				(type default)
			)
			(layer "F.SilkS")
		)
		(fp_line
			(start -0.7874 0.4064)
			(end -0.7874 -0.4064)
			(stroke
				(width 0.1524)
				(type default)
			)
			(layer "F.SilkS")
		)
		(fp_line
			(start 0.7874 -0.4064)
			(end 0.7874 0.4064)
			(stroke
				(width 0.1524)
				(type default)
			)
			(layer "F.SilkS")
		)
		(fp_line
			(start 0.7874 0.4064)
			(end -0.7874 0.4064)
			(stroke
				(width 0.1524)
				(type default)
			)
			(layer "F.SilkS")
		)
		(fp_line
			(start -0.67945 -0.305054)
			(end -0.12065 -0.305054)
			(stroke
				(width 0.1)
				(type default)
			)
			(layer "F.Fab")
		)
		(fp_line
			(start -0.67945 0.3048)
			(end -0.67945 -0.305054)
			(stroke
				(width 0.1)
				(type default)
			)
			(layer "F.Fab")
		)
		(fp_line
			(start -0.12065 -0.305054)
			(end -0.12065 -0.2794)
			(stroke
				(width 0.1)
				(type default)
			)
			(layer "F.Fab")
		)
		(fp_line
			(start -0.12065 -0.2794)
			(end 0.12065 -0.2794)
			(stroke
				(width 0.1)
				(type default)
			)
			(layer "F.Fab")
		)
		(fp_line
			(start -0.12065 0.2794)
			(end -0.12065 0.3048)
			(stroke
				(width 0.1)
				(type default)
			)
			(layer "F.Fab")
		)
		(fp_line
			(start -0.12065 0.3048)
			(end -0.67945 0.3048)
			(stroke
				(width 0.1)
				(type default)
			)
			(layer "F.Fab")
		)
		(fp_line
			(start 0.120396 0.2794)
			(end -0.12065 0.2794)
			(stroke
				(width 0.1)
				(type default)
			)
			(layer "F.Fab")
		)
		(fp_line
			(start 0.120396 0.3048)
			(end 0.120396 0.2794)
			(stroke
				(width 0.1)
				(type default)
			)
			(layer "F.Fab")
		)
		(fp_line
			(start 0.12065 -0.3048)
			(end 0.67945 -0.3048)
			(stroke
				(width 0.1)
				(type default)
			)
			(layer "F.Fab")
		)
		(fp_line
			(start 0.12065 -0.2794)
			(end 0.12065 -0.3048)
			(stroke
				(width 0.1)
				(type default)
			)
			(layer "F.Fab")
		)
		(fp_line
			(start 0.67945 -0.3048)
			(end 0.67945 0.3048)
			(stroke
				(width 0.1)
				(type default)
			)
			(layer "F.Fab")
		)
		(fp_line
			(start 0.67945 0.3048)
			(end 0.120396 0.3048)
			(stroke
				(width 0.1)
				(type default)
			)
			(layer "F.Fab")
		)
		(pad "1" smd circle
			(at -0.40005 0)
			(size 0 0)
			(layers "F.Cu" "F.Mask" "F.Paste")
			(net "P12V_OCP_V3_2")
		)
		(pad "2" smd circle
			(at 0.40005 0)
			(size 0 0)
			(layers "F.Cu" "F.Mask" "F.Paste")
			(net "GND")
		)
	)
	(footprint ""
		(layer "F.Cu")
		(at 101.046026 -357.126032 -90)
		(property "Reference" "C2448"
			(at 0 0 270)
			(layer "F.SilkS")
			(hide yes)
			(effects
				(font
					(size 1.27 1.27)
				)
			)
		)
		(property "Value" ""
			(at 0 0 270)
			(layer "F.Fab")
			(effects
				(font
					(size 1.27 1.27)
				)
			)
		)
		(duplicate_pad_numbers_are_jumpers no)
		(fp_line
			(start -1.2954 0.5842)
			(end -1.2954 -0.5842)
			(stroke
				(width 0.1524)
				(type default)
			)
			(layer "F.SilkS")
		)
		(fp_line
			(start 1.2954 0.5842)
			(end -1.2954 0.5842)
			(stroke
				(width 0.1524)
				(type default)
			)
			(layer "F.SilkS")
		)
		(fp_line
			(start -1.2954 -0.5842)
			(end 1.2954 -0.5842)
			(stroke
				(width 0.1524)
				(type default)
			)
			(layer "F.SilkS")
		)
		(fp_line
			(start 0 -0.5842)
			(end 0 0.5842)
			(stroke
				(width 0.1524)
				(type default)
			)
			(layer "F.SilkS")
		)
		(fp_line
			(start 1.2954 -0.5842)
			(end 1.2954 0.5842)
			(stroke
				(width 0.1524)
				(type default)
			)
			(layer "F.SilkS")
		)
		(fp_line
			(start -0.8636 0.4572)
			(end -0.8636 0.4064)
			(stroke
				(width 0.1)
				(type default)
			)
			(layer "F.Fab")
		)
		(fp_line
			(start 0.8636 0.4572)
			(end -0.8636 0.4572)
			(stroke
				(width 0.1)
				(type default)
			)
			(layer "F.Fab")
		)
		(fp_line
			(start -1.1938 0.4064)
			(end -1.1938 -0.4064)
			(stroke
				(width 0.1)
				(type default)
			)
			(layer "F.Fab")
		)
		(fp_line
			(start -0.8636 0.4064)
			(end -1.1938 0.4064)
			(stroke
				(width 0.1)
				(type default)
			)
			(layer "F.Fab")
		)
		(fp_line
			(start 0.8636 0.4064)
			(end 0.8636 0.4572)
			(stroke
				(width 0.1)
				(type default)
			)
			(layer "F.Fab")
		)
		(fp_line
			(start 1.1938 0.4064)
			(end 0.8636 0.4064)
			(stroke
				(width 0.1)
				(type default)
			)
			(layer "F.Fab")
		)
		(fp_line
			(start -1.1938 -0.4064)
			(end -0.8636 -0.4064)
			(stroke
				(width 0.1)
				(type default)
			)
			(layer "F.Fab")
		)
		(fp_line
			(start -0.8636 -0.4064)
			(end -0.8636 -0.4572)
			(stroke
				(width 0.1)
				(type default)
			)
			(layer "F.Fab")
		)
		(fp_line
			(start 0.8636 -0.4064)
			(end 1.1938 -0.4064)
			(stroke
				(width 0.1)
				(type default)
			)
			(layer "F.Fab")
		)
		(fp_line
			(start 1.1938 -0.4064)
			(end 1.1938 0.4064)
			(stroke
				(width 0.1)
				(type default)
			)
			(layer "F.Fab")
		)
		(fp_line
			(start -0.8636 -0.4572)
			(end 0.8636 -0.4572)
			(stroke
				(width 0.1)
				(type default)
			)
			(layer "F.Fab")
		)
		(fp_line
			(start 0.8636 -0.4572)
			(end 0.8636 -0.4064)
			(stroke
				(width 0.1)
				(type default)
			)
			(layer "F.Fab")
		)
		(pad "1" smd rect
			(at -0.7366 0 180)
			(size 0.7112 0.8128)
			(layers "F.Cu" "F.Mask" "F.Paste")
			(net "PVNN_TERM_CPU1")
		)
		(pad "2" smd rect
			(at 0.7366 0 180)
			(size 0.7112 0.8128)
			(layers "F.Cu" "F.Mask" "F.Paste")
			(net "GND")
		)
	)
)
